# T6G (Grand Teton) — schematic netlist excerpt (pin names and nets, part order shuffled) for the footprints in the layout excerpt that follows; sources: Cadence DE-HDL packaged netlist, KiCad conversion of 04192023_DAF0TMB3IC0_F0TG_MB_C_brd_V02_OCP.brd

R625  Q_RES  51.1 1% EMPTY  pkg 0201LF  page 331 : A = CLK_100M_RETIMER_CPU1_P1_DN ; B = GND
R1800  Q_RES  1.21K 1% CHIP  pkg 0402LF  page 257 : A = P12V_AUX_ADC ; B = GND
C2041  Q_CAP  1UF 25V 10% X6S  pkg C0402  page 234 : A = RST_USB_HUB_R_N ; B = GND

(kicad_pcb
	(version 20260206)
	(generator "pcbnew")
	(generator_version "10.0")
	(general
		(thickness 1.6)
		(legacy_teardrops no)
	)
	(paper "A4")
	(title_block
		(title "04192023_DAF0TMB3IC0_F0TG_MB_C_brd_V02_OCP.brd")
		(comment 1 "Grand Teton / footprints 1495-1497 of 8354")
	)
	(layers
		(0 "F.Cu" signal "TOP")
		(4 "In1.Cu" signal "GND")
		(6 "In2.Cu" signal "IN1")
		(8 "In3.Cu" signal "GND1")
		(10 "In4.Cu" signal "IN2")
		(12 "In5.Cu" signal "GND2")
		(14 "In6.Cu" signal "IN3")
		(16 "In7.Cu" signal "GND3")
		(18 "In8.Cu" signal "VCC")
		(20 "In9.Cu" signal "VCC1")
		(22 "In10.Cu" signal "GND4")
		(24 "In11.Cu" signal "IN4")
		(26 "In12.Cu" signal "GND5")
		(28 "In13.Cu" signal "IN5")
		(30 "In14.Cu" signal "GND6")
		(32 "In15.Cu" signal "IN6")
		(34 "In16.Cu" signal "GND7")
		(2 "B.Cu" signal "BOTTOM")
		(9 "F.Adhes" user "F.Adhesive")
		(11 "B.Adhes" user "B.Adhesive")
		(13 "F.Paste" user "Package Geometry/Pastemask Top")
		(15 "B.Paste" user "Package Geometry/Pastemask Bottom")
		(5 "F.SilkS" user "Ref Des/Silkscreen Top")
		(7 "B.SilkS" user "Ref Des/Silkscreen Bottom")
		(1 "F.Mask" user "Board Geometry/Soldermask Top")
		(3 "B.Mask" user "Board Geometry/Soldermask Bottom")
		(17 "Dwgs.User" user "User.Drawings")
		(19 "Cmts.User" user "User.Comments")
		(21 "Eco1.User" user "User.Eco1")
		(23 "Eco2.User" user "User.Eco2")
		(25 "Edge.Cuts" user "Board Geometry/Outline")
		(27 "Margin" user)
		(31 "F.CrtYd" user "Package Geometry/Place Bound Top")
		(29 "B.CrtYd" user "Package Geometry/Place Bound Bottom")
		(35 "F.Fab" user "Ref Des/Assembly Top")
		(33 "B.Fab" user "Ref Des/Assembly Bottom")
	)
	(footprint ""
		(layer "F.Cu")
		(at 11.895836 -92.687648 -90)
		(property "Reference" "C2041"
			(at 0 0 270)
			(layer "F.SilkS")
			(hide yes)
			(effects
				(font
					(size 1.27 1.27)
				)
			)
		)
		(property "Value" ""
			(at 0 0 270)
			(layer "F.Fab")
			(effects
				(font
					(size 1.27 1.27)
				)
			)
		)
		(duplicate_pad_numbers_are_jumpers no)
		(fp_line
			(start -0.7874 0.4064)
			(end -0.7874 -0.4064)
			(stroke
				(width 0.1524)
				(type default)
			)
			(layer "F.SilkS")
		)
		(fp_line
			(start 0.7874 0.4064)
			(end -0.7874 0.4064)
			(stroke
				(width 0.1524)
				(type default)
			)
			(layer "F.SilkS")
		)
		(fp_line
			(start -0.7874 -0.4064)
			(end 0.7874 -0.4064)
			(stroke
				(width 0.1524)
				(type default)
			)
			(layer "F.SilkS")
		)
		(fp_line
			(start 0.7874 -0.4064)
			(end 0.7874 0.4064)
			(stroke
				(width 0.1524)
				(type default)
			)
			(layer "F.SilkS")
		)
		(fp_line
			(start -0.67945 0.3048)
			(end -0.67945 -0.305054)
			(stroke
				(width 0.1)
				(type default)
			)
			(layer "F.Fab")
		)
		(fp_line
			(start -0.12065 0.3048)
			(end -0.67945 0.3048)
			(stroke
				(width 0.1)
				(type default)
			)
			(layer "F.Fab")
		)
		(fp_line
			(start 0.120396 0.3048)
			(end 0.120396 0.2794)
			(stroke
				(width 0.1)
				(type default)
			)
			(layer "F.Fab")
		)
		(fp_line
			(start 0.67945 0.3048)
			(end 0.120396 0.3048)
			(stroke
				(width 0.1)
				(type default)
			)
			(layer "F.Fab")
		)
		(fp_line
			(start -0.12065 0.2794)
			(end -0.12065 0.3048)
			(stroke
				(width 0.1)
				(type default)
			)
			(layer "F.Fab")
		)
		(fp_line
			(start 0.120396 0.2794)
			(end -0.12065 0.2794)
			(stroke
				(width 0.1)
				(type default)
			)
			(layer "F.Fab")
		)
		(fp_line
			(start -0.12065 -0.2794)
			(end 0.12065 -0.2794)
			(stroke
				(width 0.1)
				(type default)
			)
			(layer "F.Fab")
		)
		(fp_line
			(start 0.12065 -0.2794)
			(end 0.12065 -0.3048)
			(stroke
				(width 0.1)
				(type default)
			)
			(layer "F.Fab")
		)
		(fp_line
			(start 0.12065 -0.3048)
			(end 0.67945 -0.3048)
			(stroke
				(width 0.1)
				(type default)
			)
			(layer "F.Fab")
		)
		(fp_line
			(start 0.67945 -0.3048)
			(end 0.67945 0.3048)
			(stroke
				(width 0.1)
				(type default)
			)
			(layer "F.Fab")
		)
		(fp_line
			(start -0.67945 -0.305054)
			(end -0.12065 -0.305054)
			(stroke
				(width 0.1)
				(type default)
			)
			(layer "F.Fab")
		)
		(fp_line
			(start -0.12065 -0.305054)
			(end -0.12065 -0.2794)
			(stroke
				(width 0.1)
				(type default)
			)
			(layer "F.Fab")
		)
		(pad "1" smd circle
			(at -0.40005 0 270)
			(size 0 0)
			(layers "F.Cu" "F.Mask" "F.Paste")
			(net "RST_USB_HUB_R_N")
		)
		(pad "2" smd circle
			(at 0.40005 0 270)
			(size 0 0)
			(layers "F.Cu" "F.Mask" "F.Paste")
			(net "GND")
		)
	)
	(footprint ""
		(layer "F.Cu")
		(at 327.179178 -46.748954)
		(property "Reference" "R1800"
			(at 0 0 0)
			(layer "F.SilkS")
			(hide yes)
			(effects
				(font
					(size 1.27 1.27)
				)
			)
		)
		(property "Value" ""
			(at 0 0 0)
			(layer "F.Fab")
			(effects
				(font
					(size 1.27 1.27)
				)
			)
		)
		(duplicate_pad_numbers_are_jumpers no)
		(fp_line
			(start -0.7874 -0.4064)
			(end 0.7874 -0.4064)
			(stroke
				(width 0.1524)
				(type default)
			)
			(layer "F.SilkS")
		)
		(fp_line
			(start -0.7874 0.4064)
			(end -0.7874 -0.4064)
			(stroke
				(width 0.1524)
				(type default)
			)
			(layer "F.SilkS")
		)
		(fp_line
			(start 0.7874 -0.4064)
			(end 0.7874 0.4064)
			(stroke
				(width 0.1524)
				(type default)
			)
			(layer "F.SilkS")
		)
		(fp_line
			(start 0.7874 0.4064)
			(end -0.7874 0.4064)
			(stroke
				(width 0.1524)
				(type default)
			)
			(layer "F.SilkS")
		)
		(fp_line
			(start -0.67945 -0.305054)
			(end -0.12065 -0.305054)
			(stroke
				(width 0.1)
				(type default)
			)
			(layer "F.Fab")
		)
		(fp_line
			(start -0.67945 0.3048)
			(end -0.67945 -0.305054)
			(stroke
				(width 0.1)
				(type default)
			)
			(layer "F.Fab")
		)
		(fp_line
			(start -0.12065 -0.305054)
			(end -0.12065 -0.2794)
			(stroke
				(width 0.1)
				(type default)
			)
			(layer "F.Fab")
		)
		(fp_line
			(start -0.12065 -0.2794)
			(end 0.12065 -0.2794)
			(stroke
				(width 0.1)
				(type default)
			)
			(layer "F.Fab")
		)
		(fp_line
			(start -0.12065 0.2794)
			(end -0.12065 0.3048)
			(stroke
				(width 0.1)
				(type default)
			)
			(layer "F.Fab")
		)
		(fp_line
			(start -0.12065 0.3048)
			(end -0.67945 0.3048)
			(stroke
				(width 0.1)
				(type default)
			)
			(layer "F.Fab")
		)
		(fp_line
			(start 0.120396 0.2794)
			(end -0.12065 0.2794)
			(stroke
				(width 0.1)
				(type default)
			)
			(layer "F.Fab")
		)
		(fp_line
			(start 0.120396 0.3048)
			(end 0.120396 0.2794)
			(stroke
				(width 0.1)
				(type default)
			)
			(layer "F.Fab")
		)
		(fp_line
			(start 0.12065 -0.3048)
			(end 0.67945 -0.3048)
			(stroke
				(width 0.1)
				(type default)
			)
			(layer "F.Fab")
		)
		(fp_line
			(start 0.12065 -0.2794)
			(end 0.12065 -0.3048)
			(stroke
				(width 0.1)
				(type default)
			)
			(layer "F.Fab")
		)
		(fp_line
			(start 0.67945 -0.3048)
			(end 0.67945 0.3048)
			(stroke
				(width 0.1)
				(type default)
			)
			(layer "F.Fab")
		)
		(fp_line
			(start 0.67945 0.3048)
			(end 0.120396 0.3048)
			(stroke
				(width 0.1)
				(type default)
			)
			(layer "F.Fab")
		)
		(pad "1" smd circle
			(at -0.40005 0)
			(size 0 0)
			(layers "F.Cu" "F.Mask" "F.Paste")
			(net "P12V_AUX_ADC")
		)
		(pad "2" smd circle
			(at 0.40005 0)
			(size 0 0)
			(layers "F.Cu" "F.Mask" "F.Paste")
			(net "GND")
		)
	)
	(footprint ""
		(layer "F.Cu")
		(at 76.07173 -386.684774 -90)
		(property "Reference" "R625"
			(at 0 0 270)
			(layer "F.SilkS")
			(hide yes)
			(effects
				(font
					(size 1.27 1.27)
				)
			)
		)
		(property "Value" ""
			(at 0 0 270)
			(layer "F.Fab")
			(effects
				(font
					(size 1.27 1.27)
				)
			)
		)
		(duplicate_pad_numbers_are_jumpers no)
		(fp_line
			(start -0.32512 0.175006)
			(end -0.32512 -0.175006)
			(stroke
				(width 0.1)
				(type default)
			)
			(layer "F.Fab")
		)
		(fp_line
			(start 0.32512 0.175006)
			(end -0.32512 0.175006)
			(stroke
				(width 0.1)
				(type default)
			)
			(layer "F.Fab")
		)
		(fp_line
			(start -0.32512 -0.175006)
			(end 0.32512 -0.175006)
			(stroke
				(width 0.1)
				(type default)
			)
			(layer "F.Fab")
		)
		(fp_line
			(start 0.32512 -0.175006)
			(end 0.32512 0.175006)
			(stroke
				(width 0.1)
				(type default)
			)
			(layer "F.Fab")
		)
		(pad "1" smd rect
			(at -0.2667 0 270)
			(size 0.3048 0.381)
			(layers "F.Cu" "F.Mask" "F.Paste")
			(net "CLK_100M_RETIMER_CPU1_P1_DN")
		)
		(pad "2" smd rect
			(at 0.2667 0 90)
			(size 0.3048 0.381)
			(layers "F.Cu" "F.Mask" "F.Paste")
			(net "GND")
		)
	)
)
